(kicad_pcb
	(version 20241229)
	(generator "pcbnew")
	(generator_version "9.0")
	(general
		(thickness 1.62)
		(legacy_teardrops no)
	)
	(paper "A3")
	(title_block
		(title "COM Express 7 Baseboard")
		(date "2025-02-04")
		(rev "1.1.2")
		(company "Antmicro Ltd")
		(comment 1 "www.antmicro.com")
		(comment 9 "footprints 146-149 of 802")
	)
	(layers
		(0 "F.Cu" signal)
		(4 "In1.Cu" signal)
		(6 "In2.Cu" signal)
		(8 "In3.Cu" signal)
		(10 "In4.Cu" signal)
		(12 "In5.Cu" signal)
		(14 "In6.Cu" signal)
		(2 "B.Cu" signal)
		(9 "F.Adhes" user "F.Adhesive")
		(11 "B.Adhes" user "B.Adhesive")
		(13 "F.Paste" user)
		(15 "B.Paste" user)
		(5 "F.SilkS" user "F.Silkscreen")
		(7 "B.SilkS" user "B.Silkscreen")
		(1 "F.Mask" user)
		(3 "B.Mask" user)
		(17 "Dwgs.User" user "User.Drawings")
		(19 "Cmts.User" user "User.Comments")
		(21 "Eco1.User" user "User.Eco1")
		(23 "Eco2.User" user "User.Eco2")
		(25 "Edge.Cuts" user)
		(27 "Margin" user)
		(31 "F.CrtYd" user "F.Courtyard")
		(29 "B.CrtYd" user "B.Courtyard")
		(35 "F.Fab" user)
		(33 "B.Fab" user)
	)
	(footprint "antmicro-footprints:C_Pol_EIA-D"
		(layer "F.Cu")
		(at 317.324999 103.3 90)
		(property "Reference" "C39"
			(at -5.96 2.375001 90)
			(layer "F.SilkS")
			(effects
				(font
					(size 0.7 0.7)
					(thickness 0.15)
				)
				(justify left bottom)
			)
		)
		(property "Value" "C_Pol_68u_16V_Panasonic-TQC-D"
			(at 0 3.4 90)
			(layer "F.Fab")
			(effects
				(font
					(size 0.7 0.7)
					(thickness 0.15)
				)
				(justify left bottom)
			)
		)
		(property "Datasheet" "https://industrial.panasonic.com/sa/products/pt/aluminum-cap-smd/models/16TQC68MYF"
			(at 0 0 90)
			(layer "F.Fab")
			(hide yes)
			(effects
				(font
					(size 1.27 1.27)
					(thickness 0.15)
				)
			)
		)
		(property "Author" "Antmicro"
			(at 420.624999 -214.024999 0)
			(layer "F.Fab")
			(hide yes)
			(effects
				(font
					(size 1 1)
					(thickness 0.15)
				)
			)
		)
		(property "Dielectric" "template_dielectric"
			(at 420.624999 -214.024999 0)
			(layer "F.Fab")
			(hide yes)
			(effects
				(font
					(size 1 1)
					(thickness 0.15)
				)
			)
		)
		(property "License" "Apache-2.0"
			(at 420.624999 -214.024999 0)
			(layer "F.Fab")
			(hide yes)
			(effects
				(font
					(size 1 1)
					(thickness 0.15)
				)
			)
		)
		(property "MPN" "16TQC68MYF"
			(at 420.624999 -214.024999 0)
			(layer "F.Fab")
			(hide yes)
			(effects
				(font
					(size 1 1)
					(thickness 0.15)
				)
			)
		)
		(property "Manufacturer" "Panasonic"
			(at 420.624999 -214.024999 0)
			(layer "F.Fab")
			(hide yes)
			(effects
				(font
					(size 1 1)
					(thickness 0.15)
				)
			)
		)
		(property "Public" "False"
			(at 420.624999 -214.024999 0)
			(layer "F.Fab")
			(hide yes)
			(effects
				(font
					(size 1 1)
					(thickness 0.15)
				)
			)
		)
		(property "Val" "68u"
			(at 420.624999 -214.024999 0)
			(layer "F.Fab")
			(hide yes)
			(effects
				(font
					(size 1 1)
					(thickness 0.15)
				)
			)
		)
		(property "Voltage" "16V"
			(at 420.624999 -214.024999 0)
			(layer "F.Fab")
			(hide yes)
			(effects
				(font
					(size 1 1)
					(thickness 0.15)
				)
			)
		)
		(sheetname "Power")
		(sheetfile "power.kicad_sch")
		(attr smd)
		(fp_line
			(start 3.6 -2.2)
			(end 3.6 -1.6)
			(stroke
				(width 0.15)
				(type solid)
			)
			(layer "F.SilkS")
		)
		(fp_line
			(start -3.58 -2.2)
			(end 3.6 -2.2)
			(stroke
				(width 0.15)
				(type solid)
			)
			(layer "F.SilkS")
		)
		(fp_line
			(start -4.1 -2.025)
			(end -4.1 -1.625)
			(stroke
				(width 0.12)
				(type solid)
			)
			(layer "F.SilkS")
		)
		(fp_line
			(start -4.3 -1.825)
			(end -3.9 -1.825)
			(stroke
				(width 0.12)
				(type solid)
			)
			(layer "F.SilkS")
		)
		(fp_line
			(start -3.58 -1.6)
			(end -3.58 -2.2)
			(stroke
				(width 0.15)
				(type solid)
			)
			(layer "F.SilkS")
		)
		(fp_line
			(start 3.6 1.6)
			(end 3.6 2.2)
			(stroke
				(width 0.15)
				(type solid)
			)
			(layer "F.SilkS")
		)
		(fp_line
			(start 3.6 2.2)
			(end -3.58 2.2)
			(stroke
				(width 0.15)
				(type solid)
			)
			(layer "F.SilkS")
		)
		(fp_line
			(start -3.58 2.2)
			(end -3.58 1.6)
			(stroke
				(width 0.15)
				(type solid)
			)
			(layer "F.SilkS")
		)
		(fp_line
			(start 3.77 -2.4)
			(end 3.77 -1.51)
			(stroke
				(width 0.05)
				(type solid)
			)
			(layer "F.CrtYd")
		)
		(fp_line
			(start -3.775 -2.4)
			(end 3.77 -2.4)
			(stroke
				(width 0.05)
				(type solid)
			)
			(layer "F.CrtYd")
		)
		(fp_line
			(start -3.775 -2.4)
			(end -3.775 -1.5)
			(stroke
				(width 0.05)
				(type solid)
			)
			(layer "F.CrtYd")
		)
		(fp_line
			(start 4.505 -1.51)
			(end 4.505 1.5)
			(stroke
				(width 0.05)
				(type solid)
			)
			(layer "F.CrtYd")
		)
		(fp_line
			(start 3.77 -1.51)
			(end 4.505 -1.51)
			(stroke
				(width 0.05)
				(type solid)
			)
			(layer "F.CrtYd")
		)
		(fp_line
			(start -3.775 -1.5)
			(end -4.505 -1.5)
			(stroke
				(width 0.05)
				(type solid)
			)
			(layer "F.CrtYd")
		)
		(fp_line
			(start 4.505 1.51)
			(end 3.77 1.51)
			(stroke
				(width 0.05)
				(type solid)
			)
			(layer "F.CrtYd")
		)
		(fp_line
			(start 3.77 1.51)
			(end 3.77 2.4)
			(stroke
				(width 0.05)
				(type solid)
			)
			(layer "F.CrtYd")
		)
		(fp_line
			(start -3.77 1.51)
			(end -4.505 1.51)
			(stroke
				(width 0.05)
				(type solid)
			)
			(layer "F.CrtYd")
		)
		(fp_line
			(start -4.505 1.51)
			(end -4.505 -1.5)
			(stroke
				(width 0.05)
				(type solid)
			)
			(layer "F.CrtYd")
		)
		(fp_line
			(start 3.77 2.4)
			(end -3.77 2.4)
			(stroke
				(width 0.05)
				(type solid)
			)
			(layer "F.CrtYd")
		)
		(fp_line
			(start -3.77 2.4)
			(end -3.77 1.51)
			(stroke
				(width 0.05)
				(type solid)
			)
			(layer "F.CrtYd")
		)
		(fp_rect
			(start -3.65 -2.15)
			(end 3.65 2.15)
			(stroke
				(width 0.15)
				(type solid)
			)
			(fill no)
			(layer "F.Fab")
		)
		(pad "1" smd roundrect
			(at -3.1 0 90)
			(size 2.31 2.52)
			(layers "F.Cu" "F.Mask" "F.Paste")
			(roundrect_rratio 0.1)
			(net 62 "+12V_AON")
			(pintype "passive")
			(teardrops
				(best_length_ratio 0.2)
				(max_length 1)
				(best_width_ratio 0.9)
				(max_width 2)
				(curved_edges yes)
				(filter_ratio 0.9)
				(enabled yes)
				(allow_two_segments yes)
				(prefer_zone_connections yes)
			)
		)
		(pad "2" smd roundrect
			(at 3.1 0 90)
			(size 2.31 2.52)
			(layers "F.Cu" "F.Mask" "F.Paste")
			(roundrect_rratio 0.1)
			(net 1 "GND")
			(pintype "passive")
			(teardrops
				(best_length_ratio 0.2)
				(max_length 1)
				(best_width_ratio 0.9)
				(max_width 2)
				(curved_edges yes)
				(filter_ratio 0.9)
				(enabled yes)
				(allow_two_segments yes)
				(prefer_zone_connections yes)
			)
		)
	)
	(footprint "antmicro-footprints:SOT-23-3"
		(layer "F.Cu")
		(at 253.775 131.51 90)
		(property "Reference" "D20"
			(at 1.4 0.425 180)
			(layer "F.SilkS")
			(effects
				(font
					(size 0.7 0.7)
					(thickness 0.15)
				)
				(justify left bottom)
			)
		)
		(property "Value" "BAT54C"
			(at -1.9 2.7 90)
			(layer "F.Fab")
			(effects
				(font
					(size 0.7 0.7)
					(thickness 0.15)
				)
				(justify left bottom)
			)
		)
		(property "Datasheet" "https://diotec.com/request/datasheet/bat54.pdf"
			(at 0 0 90)
			(layer "F.Fab")
			(hide yes)
			(effects
				(font
					(size 1.27 1.27)
					(thickness 0.15)
				)
			)
		)
		(property "Author" "Antmicro"
			(at 385.285 -122.265 0)
			(layer "F.Fab")
			(hide yes)
			(effects
				(font
					(size 1 1)
					(thickness 0.15)
				)
			)
		)
		(property "License" "Apache-2.0"
			(at 385.285 -122.265 0)
			(layer "F.Fab")
			(hide yes)
			(effects
				(font
					(size 1 1)
					(thickness 0.15)
				)
			)
		)
		(property "MPN" "BAT54C"
			(at 385.285 -122.265 0)
			(layer "F.Fab")
			(hide yes)
			(effects
				(font
					(size 1 1)
					(thickness 0.15)
				)
			)
		)
		(property "Manufacturer" "Diotec Semiconductor"
			(at 385.285 -122.265 0)
			(layer "F.Fab")
			(hide yes)
			(effects
				(font
					(size 1 1)
					(thickness 0.15)
				)
			)
		)
		(sheetname "Com Express 7 MGMT")
		(sheetfile "com_express_7_mgmt.kicad_sch")
		(attr smd)
		(fp_line
			(start 0.7 -1.5)
			(end -0.7 -1.5)
			(stroke
				(width 0.15)
				(type solid)
			)
			(layer "F.SilkS")
		)
		(fp_line
			(start -0.85 -1.35)
			(end -0.7 -1.5)
			(stroke
				(width 0.15)
				(type solid)
			)
			(layer "F.SilkS")
		)
		(fp_line
			(start -1.45 -1.35)
			(end -0.85 -1.35)
			(stroke
				(width 0.15)
				(type solid)
			)
			(layer "F.SilkS")
		)
		(fp_line
			(start 0.7 -0.4)
			(end 0.7 -1.5)
			(stroke
				(width 0.15)
				(type solid)
			)
			(layer "F.SilkS")
		)
		(fp_line
			(start 0.7 0.4)
			(end 0.7 1.5)
			(stroke
				(width 0.15)
				(type solid)
			)
			(layer "F.SilkS")
		)
		(fp_line
			(start 0.7 1.5)
			(end -0.7 1.5)
			(stroke
				(width 0.15)
				(type solid)
			)
			(layer "F.SilkS")
		)
		(fp_line
			(start -0.7 1.5)
			(end -0.7 1.35)
			(stroke
				(width 0.15)
				(type solid)
			)
			(layer "F.SilkS")
		)
		(fp_line
			(start 0.825 -1.6)
			(end 0.825 -0.45)
			(stroke
				(width 0.05)
				(type solid)
			)
			(layer "F.CrtYd")
		)
		(fp_line
			(start -0.9 -1.6)
			(end 0.825 -1.6)
			(stroke
				(width 0.05)
				(type solid)
			)
			(layer "F.CrtYd")
		)
		(fp_line
			(start -0.9 -1.6)
			(end -0.9 -1.4)
			(stroke
				(width 0.05)
				(type solid)
			)
			(layer "F.CrtYd")
		)
		(fp_line
			(start -0.9 -1.4)
			(end -1.75 -1.4)
			(stroke
				(width 0.05)
				(type solid)
			)
			(layer "F.CrtYd")
		)
		(fp_line
			(start -0.85 -0.5)
			(end -1.75 -0.5)
			(stroke
				(width 0.05)
				(type solid)
			)
			(layer "F.CrtYd")
		)
		(fp_line
			(start -1.75 -0.5)
			(end -1.75 -1.4)
			(stroke
				(width 0.05)
				(type solid)
			)
			(layer "F.CrtYd")
		)
		(fp_line
			(start 1.75 -0.45)
			(end 1.75 0.45)
			(stroke
				(width 0.05)
				(type solid)
			)
			(layer "F.CrtYd")
		)
		(fp_line
			(start 0.825 -0.45)
			(end 1.75 -0.45)
			(stroke
				(width 0.05)
				(type solid)
			)
			(layer "F.CrtYd")
		)
		(fp_line
			(start 1.75 0.45)
			(end 0.85 0.45)
			(stroke
				(width 0.05)
				(type solid)
			)
			(layer "F.CrtYd")
		)
		(fp_line
			(start 0.85 0.45)
			(end 0.85 1.65)
			(stroke
				(width 0.05)
				(type solid)
			)
			(layer "F.CrtYd")
		)
		(fp_line
			(start -0.85 0.5)
			(end -0.85 -0.5)
			(stroke
				(width 0.05)
				(type solid)
			)
			(layer "F.CrtYd")
		)
		(fp_line
			(start -1.75 0.5)
			(end -0.85 0.5)
			(stroke
				(width 0.05)
				(type solid)
			)
			(layer "F.CrtYd")
		)
		(fp_line
			(start -0.85 1.4)
			(end -1.75 1.4)
			(stroke
				(width 0.05)
				(type solid)
			)
			(layer "F.CrtYd")
		)
		(fp_line
			(start -1.75 1.4)
			(end -1.75 0.5)
			(stroke
				(width 0.05)
				(type solid)
			)
			(layer "F.CrtYd")
		)
		(fp_line
			(start 0.85 1.65)
			(end -0.85 1.65)
			(stroke
				(width 0.05)
				(type solid)
			)
			(layer "F.CrtYd")
		)
		(fp_line
			(start -0.85 1.65)
			(end -0.85 1.4)
			(stroke
				(width 0.05)
				(type solid)
			)
			(layer "F.CrtYd")
		)
		(fp_line
			(start -0.437 -1.526)
			(end 0.688 -1.526)
			(stroke
				(width 0.15)
				(type solid)
			)
			(layer "F.Fab")
		)
		(fp_line
			(start -0.437 -1.526)
			(end -0.712 -1.325)
			(stroke
				(width 0.15)
				(type solid)
			)
			(layer "F.Fab")
		)
		(fp_line
			(start -0.712 -1.325)
			(end -0.712 1.523)
			(stroke
				(width 0.15)
				(type solid)
			)
			(layer "F.Fab")
		)
		(fp_line
			(start 0.688 1.519)
			(end 0.688 -1.52)
			(stroke
				(width 0.15)
				(type solid)
			)
			(layer "F.Fab")
		)
		(fp_line
			(start -0.712 1.519)
			(end 0.688 1.519)
			(stroke
				(width 0.15)
				(type solid)
			)
			(layer "F.Fab")
		)
		(pad "1" smd roundrect
			(at -1.1 -0.951 90)
			(size 1 0.6)
			(layers "F.Cu" "F.Mask" "F.Paste")
			(roundrect_rratio 0.15)
			(net 136 "/Com Express 7 MGMT/~{TYPE0}")
			(pinfunction "1")
			(pintype "passive")
			(teardrops
				(best_length_ratio 0.2)
				(max_length 1)
				(best_width_ratio 0.9)
				(max_width 2)
				(curved_edges yes)
				(filter_ratio 0.9)
				(enabled yes)
				(allow_two_segments yes)
				(prefer_zone_connections yes)
			)
		)
		(pad "2" smd roundrect
			(at -1.1 0.949 90)
			(size 1 0.6)
			(layers "F.Cu" "F.Mask" "F.Paste")
			(roundrect_rratio 0.15)
			(net 137 "/Com Express 7 MGMT/~{TYPE2}")
			(pinfunction "2")
			(pintype "passive")
			(teardrops
				(best_length_ratio 0.2)
				(max_length 1)
				(best_width_ratio 0.9)
				(max_width 2)
				(curved_edges yes)
				(filter_ratio 0.9)
				(enabled yes)
				(allow_two_segments yes)
				(prefer_zone_connections yes)
			)
		)
		(pad "3" smd roundrect
			(at 1.1 -0.0005 90)
			(size 1 0.6)
			(layers "F.Cu" "F.Mask" "F.Paste")
			(roundrect_rratio 0.15)
			(net 138 "Net-(U33-1A)")
			(pinfunction "3")
			(pintype "passive")
			(teardrops
				(best_length_ratio 0.2)
				(max_length 1)
				(best_width_ratio 0.9)
				(max_width 2)
				(curved_edges yes)
				(filter_ratio 0.9)
				(enabled yes)
				(allow_two_segments yes)
				(prefer_zone_connections yes)
			)
		)
	)
	(footprint "antmicro-footprints:R_0402_1005Metric"
		(layer "F.Cu")
		(at 299.2 84.01 -90)
		(descr "Resistor SMD 0402")
		(tags "resistor SMD 0402")
		(property "Reference" "R128"
			(at 0.85 -0.45 90)
			(layer "F.SilkS")
			(effects
				(font
					(size 0.7 0.7)
					(thickness 0.15)
				)
				(justify right bottom)
			)
		)
		(property "Value" "R_10k_0402"
			(at -1.011843 1.772047 90)
			(layer "F.Fab")
			(effects
				(font
					(size 0.7 0.7)
					(thickness 0.15)
				)
				(justify right bottom)
			)
		)
		(property "Datasheet" "https://www.bourns.com/docs/product-datasheets/cr.pdf"
			(at 0 0 270)
			(layer "F.Fab")
			(hide yes)
			(effects
				(font
					(size 1.27 1.27)
					(thickness 0.15)
				)
			)
		)
		(property "Author" "Antmicro"
			(at 215.19 383.21 0)
			(layer "F.Fab")
			(hide yes)
			(effects
				(font
					(size 1 1)
					(thickness 0.15)
				)
			)
		)
		(property "License" "Apache-2.0"
			(at 215.19 383.21 0)
			(layer "F.Fab")
			(hide yes)
			(effects
				(font
					(size 1 1)
					(thickness 0.15)
				)
			)
		)
		(property "MPN" "CR0402-FX-1002GLF"
			(at 215.19 383.21 0)
			(layer "F.Fab")
			(hide yes)
			(effects
				(font
					(size 1 1)
					(thickness 0.15)
				)
			)
		)
		(property "Manufacturer" "Bourns"
			(at 215.19 383.21 0)
			(layer "F.Fab")
			(hide yes)
			(effects
				(font
					(size 1 1)
					(thickness 0.15)
				)
			)
		)
		(property "Public" "False"
			(at 215.19 383.21 0)
			(layer "F.Fab")
			(hide yes)
			(effects
				(font
					(size 1 1)
					(thickness 0.15)
				)
			)
		)
		(property "Tolerance" "1%"
			(at 215.19 383.21 0)
			(layer "F.Fab")
			(hide yes)
			(effects
				(font
					(size 1 1)
					(thickness 0.15)
				)
			)
		)
		(property "Val" "10k"
			(at 215.19 383.21 0)
			(layer "F.Fab")
			(hide yes)
			(effects
				(font
					(size 1 1)
					(thickness 0.15)
				)
			)
		)
		(sheetname "M.2 key M #2")
		(sheetfile "m2keym.kicad_sch")
		(attr smd)
		(fp_rect
			(start -0.925 -0.47)
			(end 0.925 0.47)
			(stroke
				(width 0.05)
				(type default)
			)
			(fill no)
			(layer "F.CrtYd")
		)
		(fp_rect
			(start -0.5 -0.25)
			(end 0.5 0.25)
			(stroke
				(width 0.15)
				(type solid)
			)
			(fill no)
			(layer "F.Fab")
		)
		(pad "1" smd roundrect
			(at -0.48 0 270)
			(size 0.59 0.64)
			(layers "F.Cu" "F.Mask" "F.Paste")
			(roundrect_rratio 0.25)
			(net 530 "/M.2 key M #2/~{CLKREQ}")
			(pintype "passive")
			(teardrops
				(best_length_ratio 0.2)
				(max_length 1)
				(best_width_ratio 0.9)
				(max_width 2)
				(curved_edges yes)
				(filter_ratio 0.9)
				(enabled yes)
				(allow_two_segments yes)
				(prefer_zone_connections yes)
			)
		)
		(pad "2" smd roundrect
			(at 0.48 0 270)
			(size 0.59 0.64)
			(layers "F.Cu" "F.Mask" "F.Paste")
			(roundrect_rratio 0.25)
			(net 2 "+3V3")
			(pintype "passive")
			(teardrops
				(best_length_ratio 0.2)
				(max_length 1)
				(best_width_ratio 0.9)
				(max_width 2)
				(curved_edges yes)
				(filter_ratio 0.9)
				(enabled yes)
				(allow_two_segments yes)
				(prefer_zone_connections yes)
			)
		)
	)
	(footprint "antmicro-footprints:C_0402_1005Metric"
		(layer "F.Cu")
		(at 195.401343 135.633266 -45)
		(descr "Capacitor SMD 0402")
		(tags "capacitor SMD 0402")
		(property "Reference" "C135"
			(at 3.864616 -0.431761 135)
			(layer "F.SilkS")
			(effects
				(font
					(size 0.7 0.7)
					(thickness 0.15)
				)
				(justify right top)
			)
		)
		(property "Value" "C_100n_0402"
			(at -1.022927 2.155213 135)
			(layer "F.Fab")
			(effects
				(font
					(size 0.7 0.7)
					(thickness 0.15)
				)
				(justify right top)
			)
		)
		(property "Datasheet" "https://www.murata.com/products/productdetail?partno=GRM155R61H104KE14%23"
			(at 0 0 135)
			(layer "B.Fab")
			(hide yes)
			(effects
				(font
					(size 1.27 1.27)
					(thickness 0.15)
				)
				(justify mirror)
			)
		)
		(property "Author" "Antmicro"
			(at 51.168 -324.134 45)
			(layer "F.Fab")
			(hide yes)
			(effects
				(font
					(size 1 1)
					(thickness 0.15)
				)
			)
		)
		(property "Dielectric" "X5R"
			(at 51.168 -324.134 45)
			(layer "F.Fab")
			(hide yes)
			(effects
				(font
					(size 1 1)
					(thickness 0.15)
				)
			)
		)
		(property "License" "Apache-2.0"
			(at 51.168 -324.134 45)
			(layer "F.Fab")
			(hide yes)
			(effects
				(font
					(size 1 1)
					(thickness 0.15)
				)
			)
		)
		(property "MPN" "GRM155R61H104KE14D"
			(at 51.168 -324.134 45)
			(layer "F.Fab")
			(hide yes)
			(effects
				(font
					(size 1 1)
					(thickness 0.15)
				)
			)
		)
		(property "Manufacturer" "Murata"
			(at 51.168 -324.134 45)
			(layer "F.Fab")
			(hide yes)
			(effects
				(font
					(size 1 1)
					(thickness 0.15)
				)
			)
		)
		(property "Public" "False"
			(at 51.168 -324.134 45)
			(layer "F.Fab")
			(hide yes)
			(effects
				(font
					(size 1 1)
					(thickness 0.15)
				)
			)
		)
		(property "Val" "100n"
			(at 51.168 -324.134 45)
			(layer "F.Fab")
			(hide yes)
			(effects
				(font
					(size 1 1)
					(thickness 0.15)
				)
			)
		)
		(property "Voltage" "50V"
			(at 51.168 -324.134 45)
			(layer "F.Fab")
			(hide yes)
			(effects
				(font
					(size 1 1)
					(thickness 0.15)
				)
			)
		)
		(sheetname "PCIe redriver")
		(sheetfile "pcie_redriver.kicad_sch")
		(attr smd)
		(fp_poly
			(pts
				(xy -0.925 -0.47) (xy 0.925 -0.47) (xy 0.925 0.47) (xy -0.925 0.47)
			)
			(stroke
				(width 0.05)
				(type default)
			)
			(fill no)
			(layer "F.CrtYd")
		)
		(fp_line
			(start -0.494 0.248)
			(end -0.494 -0.25)
			(stroke
				(width 0.15)
				(type solid)
			)
			(layer "F.Fab")
		)
		(fp_line
			(start -0.494 -0.25)
			(end 0.504 -0.25)
			(stroke
				(width 0.15)
				(type solid)
			)
			(layer "F.Fab")
		)
		(fp_line
			(start 0.504 0.248)
			(end -0.494 0.248)
			(stroke
				(width 0.15)
				(type solid)
			)
			(layer "F.Fab")
		)
		(fp_line
			(start 0.504 -0.25)
			(end 0.504 0.248)
			(stroke
				(width 0.15)
				(type solid)
			)
			(layer "F.Fab")
		)
		(pad "1" smd roundrect
			(at -0.48 0 315)
			(size 0.59 0.64)
			(layers "F.Cu" "F.Mask" "F.Paste")
			(roundrect_rratio 0.25)
			(net 1 "GND")
			(pintype "passive")
			(teardrops
				(best_length_ratio 0.2)
				(max_length 1)
				(best_width_ratio 0.9)
				(max_width 2)
				(curved_edges yes)
				(filter_ratio 0.9)
				(enabled yes)
				(allow_two_segments yes)
				(prefer_zone_connections yes)
			)
		)
		(pad "2" smd roundrect
			(at 0.48 0 315)
			(size 0.59 0.64)
			(layers "F.Cu" "F.Mask" "F.Paste")
			(roundrect_rratio 0.25)
			(net 2 "+3V3")
			(pintype "passive")
			(teardrops
				(best_length_ratio 0.2)
				(max_length 1)
				(best_width_ratio 0.9)
				(max_width 2)
				(curved_edges yes)
				(filter_ratio 0.9)
				(enabled yes)
				(allow_two_segments yes)
				(prefer_zone_connections yes)
			)
		)
	)
)
